(kicad_pcb
	(version 20260206)
	(generator "pcbnew")
	(generator_version "10.0")
	(general
		(thickness 1.6)
		(legacy_teardrops no)
	)
	(paper "A4")
	(title_block
		(title "Bryce Canyon_R.DPB_16317-1_OCP.brd")
		(comment 1 "Bryce Canyon / footprints 1180-1187 of 2099")
	)
	(layers
		(0 "F.Cu" signal "TOP")
		(4 "In1.Cu" signal "L2GND")
		(6 "In2.Cu" signal "L3")
		(8 "In3.Cu" signal "L4VCC")
		(10 "In4.Cu" signal "L5VCC")
		(12 "In5.Cu" signal "L6")
		(14 "In6.Cu" signal "L7GND")
		(2 "B.Cu" signal "BOTTOM")
		(9 "F.Adhes" user "F.Adhesive")
		(11 "B.Adhes" user "B.Adhesive")
		(13 "F.Paste" user "Package Geometry/Pastemask Top")
		(15 "B.Paste" user "Package Geometry/Pastemask Bottom")
		(5 "F.SilkS" user "Ref Des/Silkscreen Top")
		(7 "B.SilkS" user "Ref Des/Silkscreen Bottom")
		(1 "F.Mask" user "Board Geometry/Soldermask Top")
		(3 "B.Mask" user "Board Geometry/Soldermask Bottom")
		(17 "Dwgs.User" user "User.Drawings")
		(19 "Cmts.User" user "User.Comments")
		(21 "Eco1.User" user "User.Eco1")
		(23 "Eco2.User" user "User.Eco2")
		(25 "Edge.Cuts" user "Board Geometry/Outline")
		(27 "Margin" user)
		(31 "F.CrtYd" user "Package Geometry/Place Bound Top")
		(29 "B.CrtYd" user "Package Geometry/Place Bound Bottom")
		(35 "F.Fab" user "Ref Des/Assembly Top")
		(33 "B.Fab" user "Ref Des/Assembly Bottom")
	)
	(footprint ""
		(layer "F.Cu")
		(at 167.7162 -370.205 90)
		(property "Reference" "R1058"
			(at 0 0 90)
			(layer "F.SilkS")
			(hide yes)
			(effects
				(font
					(size 1.27 1.27)
				)
			)
		)
		(property "Value" "10R2F-L-GP"
			(at 0.064008 -3.993896 90)
			(unlocked yes)
			(layer "F.Fab")
			(hide yes)
			(effects
				(font
					(size 1.016 1.016)
					(thickness 0.1524)
				)
			)
		)
		(property "Device Type" "R402H14"
			(at 0.064008 -5.517896 90)
			(unlocked yes)
			(layer "F.Fab")
			(hide yes)
			(effects
				(font
					(size 1.016 1.016)
					(thickness 0.1524)
				)
			)
		)
		(duplicate_pad_numbers_are_jumpers no)
		(fp_line
			(start 0.508 -0.9398)
			(end -0.508 -0.9398)
			(stroke
				(width 0.1524)
				(type default)
			)
			(layer "F.SilkS")
		)
		(fp_line
			(start -0.508 -0.9398)
			(end -0.508 0.9398)
			(stroke
				(width 0.1524)
				(type default)
			)
			(layer "F.SilkS")
		)
		(fp_rect
			(start -0.508 0.9398)
			(end 0.508 -0.9398)
			(stroke
				(width 0)
				(type default)
			)
			(fill no)
			(layer "F.CrtYd")
		)
		(fp_rect
			(start -0.508 0.9398)
			(end 0.508 -0.9398)
			(stroke
				(width 0)
				(type default)
			)
			(fill no)
			(layer "F.Fab")
		)
		(pad "1" smd custom
			(at 0 -0.4445 90)
			(size 0.1397 0.1397)
			(layers "F.Cu" "F.Mask" "F.Paste")
			(net "MB0_CM_SENSE_R2_N")
			(options
				(clearance outline)
				(anchor circle)
			)
			(primitives
				(gr_poly
					(pts
						(arc
							(start -0.1778 -0.2794)
							(mid -0.249642 -0.249642)
							(end -0.2794 -0.1778)
						)
						(arc
							(start -0.2794 0.1778)
							(mid -0.249642 0.249642)
							(end -0.1778 0.2794)
						)
						(arc
							(start 0.1778 0.2794)
							(mid 0.249642 0.249642)
							(end 0.2794 0.1778)
						)
						(arc
							(start 0.2794 -0.1778)
							(mid 0.249642 -0.249642)
							(end 0.1778 -0.2794)
						)
					)
					(width 0)
					(fill yes)
				)
			)
		)
		(pad "2" smd custom
			(at 0 0.4445 90)
			(size 0.1397 0.1397)
			(layers "F.Cu" "F.Mask" "F.Paste")
			(net "MB0_HS_SENSE_N")
			(options
				(clearance outline)
				(anchor circle)
			)
			(primitives
				(gr_poly
					(pts
						(arc
							(start -0.1778 -0.2794)
							(mid -0.249642 -0.249642)
							(end -0.2794 -0.1778)
						)
						(arc
							(start -0.2794 0.1778)
							(mid -0.249642 0.249642)
							(end -0.1778 0.2794)
						)
						(arc
							(start 0.1778 0.2794)
							(mid 0.249642 0.249642)
							(end 0.2794 0.1778)
						)
						(arc
							(start 0.2794 -0.1778)
							(mid 0.249642 -0.249642)
							(end 0.1778 -0.2794)
						)
					)
					(width 0)
					(fill yes)
				)
			)
		)
	)
	(footprint ""
		(layer "F.Cu")
		(at 396.6972 -155.6004 -90)
		(property "Reference" "R531"
			(at 0 0 270)
			(layer "F.SilkS")
			(hide yes)
			(effects
				(font
					(size 1.27 1.27)
				)
			)
		)
		(property "Value" "2R6F-GP"
			(at -0.0508 -4.8514 270)
			(unlocked yes)
			(layer "F.Fab")
			(hide yes)
			(effects
				(font
					(size 1.016 1.016)
					(thickness 0.1524)
				)
			)
		)
		(property "Device Type" "R1206H26"
			(at 0 -6.3754 270)
			(unlocked yes)
			(layer "F.Fab")
			(hide yes)
			(effects
				(font
					(size 1.016 1.016)
					(thickness 0.1524)
				)
			)
		)
		(duplicate_pad_numbers_are_jumpers no)
		(fp_line
			(start -1.016 2.2352)
			(end -1.016 -2.2352)
			(stroke
				(width 0.1524)
				(type default)
			)
			(layer "F.SilkS")
		)
		(fp_line
			(start 1.016 2.2352)
			(end -1.016 2.2352)
			(stroke
				(width 0.1524)
				(type default)
			)
			(layer "F.SilkS")
		)
		(fp_line
			(start -1.016 -2.2352)
			(end 1.016 -2.2352)
			(stroke
				(width 0.1524)
				(type default)
			)
			(layer "F.SilkS")
		)
		(fp_line
			(start 1.016 -2.2352)
			(end 1.016 2.2352)
			(stroke
				(width 0.1524)
				(type default)
			)
			(layer "F.SilkS")
		)
		(fp_rect
			(start -1.0922 2.3114)
			(end 1.0922 -2.3114)
			(stroke
				(width 0)
				(type default)
			)
			(fill no)
			(layer "F.CrtYd")
		)
		(fp_poly
			(pts
				(xy -1.0922 -2.3114) (xy 1.0922 -2.3114) (xy 1.0922 2.3114) (xy -1.0922 2.3114)
			)
			(stroke
				(width 0)
				(type default)
			)
			(fill no)
			(layer "F.Fab")
		)
		(pad "1" smd rect
			(at 0 -1.397 270)
			(size 1.651 1.27)
			(layers "F.Cu" "F.Mask" "F.Paste")
			(net "P12V_HDD20")
		)
		(pad "2" smd rect
			(at 0 1.397 270)
			(size 1.651 1.27)
			(layers "F.Cu" "F.Mask" "F.Paste")
			(net "12V_PRE_20")
		)
	)
	(footprint ""
		(layer "F.Cu")
		(at 181.6862 -157.226)
		(property "Reference" "C255"
			(at 0 0 0)
			(layer "F.SilkS")
			(hide yes)
			(effects
				(font
					(size 1.27 1.27)
				)
			)
		)
		(property "Value" "SC4D7U25V5KX-1-GP"
			(at -0.0762 -6.1214 0)
			(unlocked yes)
			(layer "F.Fab")
			(hide yes)
			(effects
				(font
					(size 1.016 1.016)
					(thickness 0.1524)
				)
			)
		)
		(property "Device Type" "C805H58"
			(at -0.0762 -8.1534 0)
			(unlocked yes)
			(layer "F.Fab")
			(hide yes)
			(effects
				(font
					(size 1.016 1.016)
					(thickness 0.1524)
				)
			)
		)
		(duplicate_pad_numbers_are_jumpers no)
		(fp_line
			(start 0.635 0)
			(end -0.635 0)
			(stroke
				(width 0.508)
				(type default)
			)
			(layer "F.SilkS")
		)
		(fp_rect
			(start -0.9652 1.778)
			(end 0.9652 -1.778)
			(stroke
				(width 0)
				(type default)
			)
			(fill no)
			(layer "F.CrtYd")
		)
		(fp_poly
			(pts
				(xy -0.9652 -1.778) (xy 0.9652 -1.778) (xy 0.9652 1.778) (xy -0.9652 1.778)
			)
			(stroke
				(width 0)
				(type default)
			)
			(fill no)
			(layer "F.Fab")
		)
		(pad "1" smd rect
			(at 0 -0.9652)
			(size 1.397 1.143)
			(layers "F.Cu" "F.Mask" "F.Paste")
			(net "P12V_HDD17")
		)
		(pad "2" smd rect
			(at 0 0.9652)
			(size 1.397 1.143)
			(layers "F.Cu" "F.Mask" "F.Paste")
			(net "GND")
		)
	)
	(footprint ""
		(layer "F.Cu")
		(at 14.859 -254.508 -90)
		(property "Reference" "R913"
			(at 0 0 270)
			(layer "F.SilkS")
			(hide yes)
			(effects
				(font
					(size 1.27 1.27)
				)
			)
		)
		(property "Value" "300KR2F-GP"
			(at 0.064008 -3.993896 270)
			(unlocked yes)
			(layer "F.Fab")
			(hide yes)
			(effects
				(font
					(size 1.016 1.016)
					(thickness 0.1524)
				)
			)
		)
		(property "Device Type" "R402H16"
			(at 0.064008 -5.517896 270)
			(unlocked yes)
			(layer "F.Fab")
			(hide yes)
			(effects
				(font
					(size 1.016 1.016)
					(thickness 0.1524)
				)
			)
		)
		(duplicate_pad_numbers_are_jumpers no)
		(fp_line
			(start -0.508 -0.9398)
			(end -0.508 0.9398)
			(stroke
				(width 0.1524)
				(type default)
			)
			(layer "F.SilkS")
		)
		(fp_line
			(start 0.508 -0.9398)
			(end -0.508 -0.9398)
			(stroke
				(width 0.1524)
				(type default)
			)
			(layer "F.SilkS")
		)
		(fp_rect
			(start -0.508 0.9398)
			(end 0.508 -0.9398)
			(stroke
				(width 0)
				(type default)
			)
			(fill no)
			(layer "F.CrtYd")
		)
		(fp_rect
			(start -0.508 0.9398)
			(end 0.508 -0.9398)
			(stroke
				(width 0)
				(type default)
			)
			(fill no)
			(layer "F.Fab")
		)
		(pad "1" smd custom
			(at 0 -0.4445 270)
			(size 0.1397 0.1397)
			(layers "F.Cu" "F.Mask" "F.Paste")
			(net "SW_HDD_N0")
			(options
				(clearance outline)
				(anchor circle)
			)
			(primitives
				(gr_poly
					(pts
						(arc
							(start -0.1778 -0.2794)
							(mid -0.249642 -0.249642)
							(end -0.2794 -0.1778)
						)
						(arc
							(start -0.2794 0.1778)
							(mid -0.249642 0.249642)
							(end -0.1778 0.2794)
						)
						(arc
							(start 0.1778 0.2794)
							(mid 0.249642 0.249642)
							(end 0.2794 0.1778)
						)
						(arc
							(start 0.2794 -0.1778)
							(mid 0.249642 -0.249642)
							(end 0.1778 -0.2794)
						)
					)
					(width 0)
					(fill yes)
				)
			)
		)
		(pad "2" smd custom
			(at 0 0.4445 270)
			(size 0.1397 0.1397)
			(layers "F.Cu" "F.Mask" "F.Paste")
			(net "P12V_B")
			(options
				(clearance outline)
				(anchor circle)
			)
			(primitives
				(gr_poly
					(pts
						(arc
							(start -0.1778 -0.2794)
							(mid -0.249642 -0.249642)
							(end -0.2794 -0.1778)
						)
						(arc
							(start -0.2794 0.1778)
							(mid -0.249642 0.249642)
							(end -0.1778 0.2794)
						)
						(arc
							(start 0.1778 0.2794)
							(mid 0.249642 0.249642)
							(end 0.2794 0.1778)
						)
						(arc
							(start 0.2794 -0.1778)
							(mid 0.249642 -0.249642)
							(end 0.1778 -0.2794)
						)
					)
					(width 0)
					(fill yes)
				)
			)
		)
	)
	(footprint ""
		(layer "F.Cu")
		(at 80.01 -132.588 180)
		(property "Reference" "D14"
			(at 0 0 180)
			(layer "F.SilkS")
			(hide yes)
			(effects
				(font
					(size 1.27 1.27)
				)
			)
		)
		(property "Value" "RB551V30-GP"
			(at 0 -6.7818 180)
			(unlocked yes)
			(layer "F.Fab")
			(hide yes)
			(effects
				(font
					(size 1.016 1.016)
					(thickness 0.1524)
				)
			)
		)
		(property "Device Type" "SOD323AKH38"
			(at 0 -8.6868 180)
			(unlocked yes)
			(layer "F.Fab")
			(hide yes)
			(effects
				(font
					(size 1.016 1.016)
					(thickness 0.1524)
				)
			)
		)
		(duplicate_pad_numbers_are_jumpers no)
		(fp_line
			(start 0.889 2.159)
			(end -0.889 2.159)
			(stroke
				(width 0.1524)
				(type default)
			)
			(layer "F.SilkS")
		)
		(fp_line
			(start 0.889 -1.9304)
			(end 0.889 2.159)
			(stroke
				(width 0.1524)
				(type default)
			)
			(layer "F.SilkS")
		)
		(fp_line
			(start 0.762 2.0574)
			(end -0.762 2.0574)
			(stroke
				(width 0.508)
				(type default)
			)
			(layer "F.SilkS")
		)
		(fp_line
			(start -0.889 2.159)
			(end -0.889 -1.9304)
			(stroke
				(width 0.1524)
				(type default)
			)
			(layer "F.SilkS")
		)
		(fp_line
			(start -0.889 -1.9304)
			(end 0.889 -1.9304)
			(stroke
				(width 0.1524)
				(type default)
			)
			(layer "F.SilkS")
		)
		(fp_rect
			(start -1.016 2.3114)
			(end 1.016 -2.0066)
			(stroke
				(width 0)
				(type default)
			)
			(fill no)
			(layer "F.CrtYd")
		)
		(fp_poly
			(pts
				(xy -1.016 -2.0066) (xy 1.016 -2.0066) (xy 1.016 2.3114) (xy -1.016 2.3114)
			)
			(stroke
				(width 0)
				(type default)
			)
			(fill no)
			(layer "F.Fab")
		)
		(pad "A" smd rect
			(at 0 -1.143 180)
			(size 0.5588 1.016)
			(layers "F.Cu" "F.Mask" "F.Paste")
			(net "SW_HDD_R14")
		)
		(pad "K" smd rect
			(at 0 1.143 180)
			(size 0.5588 1.016)
			(layers "F.Cu" "F.Mask" "F.Paste")
			(net "SW_HDD_N14")
		)
	)
	(footprint ""
		(layer "F.Cu")
		(at 210.93938 -235.18622)
		(property "Reference" "R39"
			(at 0 0 0)
			(layer "F.SilkS")
			(hide yes)
			(effects
				(font
					(size 1.27 1.27)
				)
			)
		)
		(property "Value" "0R2J-2-GP"
			(at 0.064008 -3.993896 0)
			(unlocked yes)
			(layer "F.Fab")
			(hide yes)
			(effects
				(font
					(size 1.016 1.016)
					(thickness 0.1524)
				)
			)
		)
		(property "Device Type" "R402H16"
			(at 0.064008 -5.517896 0)
			(unlocked yes)
			(layer "F.Fab")
			(hide yes)
			(effects
				(font
					(size 1.016 1.016)
					(thickness 0.1524)
				)
			)
		)
		(duplicate_pad_numbers_are_jumpers no)
		(fp_line
			(start -0.508 -0.9398)
			(end -0.508 0.9398)
			(stroke
				(width 0.1524)
				(type default)
			)
			(layer "F.SilkS")
		)
		(fp_line
			(start 0.508 -0.9398)
			(end -0.508 -0.9398)
			(stroke
				(width 0.1524)
				(type default)
			)
			(layer "F.SilkS")
		)
		(fp_rect
			(start -0.508 0.9398)
			(end 0.508 -0.9398)
			(stroke
				(width 0)
				(type default)
			)
			(fill no)
			(layer "F.CrtYd")
		)
		(fp_rect
			(start -0.508 0.9398)
			(end 0.508 -0.9398)
			(stroke
				(width 0)
				(type default)
			)
			(fill no)
			(layer "F.Fab")
		)
		(pad "1" smd custom
			(at 0 -0.4445)
			(size 0.1397 0.1397)
			(layers "F.Cu" "F.Mask" "F.Paste")
			(net "IO_EXP4_SDA")
			(options
				(clearance outline)
				(anchor circle)
			)
			(primitives
				(gr_poly
					(pts
						(arc
							(start -0.1778 -0.2794)
							(mid -0.249642 -0.249642)
							(end -0.2794 -0.1778)
						)
						(arc
							(start -0.2794 0.1778)
							(mid -0.249642 0.249642)
							(end -0.1778 0.2794)
						)
						(arc
							(start 0.1778 0.2794)
							(mid 0.249642 0.249642)
							(end 0.2794 0.1778)
						)
						(arc
							(start 0.2794 -0.1778)
							(mid 0.249642 -0.249642)
							(end 0.1778 -0.2794)
						)
					)
					(width 0)
					(fill yes)
				)
			)
		)
		(pad "2" smd custom
			(at 0 0.4445)
			(size 0.1397 0.1397)
			(layers "F.Cu" "F.Mask" "F.Paste")
			(net "I2C_DRIVE_B_INS_SDA")
			(options
				(clearance outline)
				(anchor circle)
			)
			(primitives
				(gr_poly
					(pts
						(arc
							(start -0.1778 -0.2794)
							(mid -0.249642 -0.249642)
							(end -0.2794 -0.1778)
						)
						(arc
							(start -0.2794 0.1778)
							(mid -0.249642 0.249642)
							(end -0.1778 0.2794)
						)
						(arc
							(start 0.1778 0.2794)
							(mid 0.249642 0.249642)
							(end 0.2794 0.1778)
						)
						(arc
							(start 0.2794 -0.1778)
							(mid 0.249642 -0.249642)
							(end 0.1778 -0.2794)
						)
					)
					(width 0)
					(fill yes)
				)
			)
		)
	)
	(footprint ""
		(layer "F.Cu")
		(at 308.193694 -214.860378 90)
		(property "Reference" "Q249"
			(at 0 0 90)
			(layer "F.SilkS")
			(hide yes)
			(effects
				(font
					(size 1.27 1.27)
				)
			)
		)
		(property "Value" "SSM3K324R-GP"
			(at 0.127 -8.9662 90)
			(unlocked yes)
			(layer "F.Fab")
			(hide yes)
			(effects
				(font
					(size 1.016 1.016)
					(thickness 0.1524)
				)
			)
		)
		(property "Device Type" "SOT23DGS2D4H35"
			(at 0.127 -10.4902 90)
			(unlocked yes)
			(layer "F.Fab")
			(hide yes)
			(effects
				(font
					(size 1.016 1.016)
					(thickness 0.1524)
				)
			)
		)
		(duplicate_pad_numbers_are_jumpers no)
		(fp_line
			(start 1.651 -1.778)
			(end -1.651 -1.778)
			(stroke
				(width 0.1524)
				(type default)
			)
			(layer "F.SilkS")
		)
		(fp_line
			(start -1.651 -1.778)
			(end -1.651 1.778)
			(stroke
				(width 0.1524)
				(type default)
			)
			(layer "F.SilkS")
		)
		(fp_line
			(start 1.651 1.778)
			(end 1.651 -1.778)
			(stroke
				(width 0.1524)
				(type default)
			)
			(layer "F.SilkS")
		)
		(fp_line
			(start -1.651 1.778)
			(end 1.651 1.778)
			(stroke
				(width 0.1524)
				(type default)
			)
			(layer "F.SilkS")
		)
		(fp_poly
			(pts
				(xy -1.778 1.8796) (xy -1.778 -1.8796) (xy 1.778 -1.8796) (xy 1.778 1.8796)
			)
			(stroke
				(width 0)
				(type default)
			)
			(fill no)
			(layer "F.CrtYd")
		)
		(fp_poly
			(pts
				(xy -1.778 1.8796) (xy -1.778 -1.8796) (xy 1.778 -1.8796) (xy 1.778 1.8796)
			)
			(stroke
				(width 0)
				(type default)
			)
			(fill no)
			(layer "F.Fab")
		)
		(pad "D" smd custom
			(at 0 -0.9525 90)
			(size 0.1905 0.1905)
			(layers "F.Cu" "F.Mask" "F.Paste")
			(net "DRV_ACT_6_N")
			(options
				(clearance outline)
				(anchor circle)
			)
			(primitives
				(gr_poly
					(pts
						(arc
							(start -0.1778 0.5715)
							(mid -0.321484 0.511984)
							(end -0.381 0.3683)
						)
						(arc
							(start -0.381 -0.3683)
							(mid -0.321484 -0.511984)
							(end -0.1778 -0.5715)
						)
						(arc
							(start 0.1778 -0.5715)
							(mid 0.321484 -0.511984)
							(end 0.381 -0.3683)
						)
						(arc
							(start 0.381 0.3683)
							(mid 0.321484 0.511984)
							(end 0.1778 0.5715)
						)
					)
					(width 0)
					(fill yes)
				)
			)
		)
		(pad "G" smd custom
			(at -0.98425 0.9525 90)
			(size 0.1905 0.1905)
			(layers "F.Cu" "F.Mask" "F.Paste")
			(net "DRIVE_B_6_ACT")
			(options
				(clearance outline)
				(anchor circle)
			)
			(primitives
				(gr_poly
					(pts
						(arc
							(start -0.1778 0.5715)
							(mid -0.321484 0.511984)
							(end -0.381 0.3683)
						)
						(arc
							(start -0.381 -0.3683)
							(mid -0.321484 -0.511984)
							(end -0.1778 -0.5715)
						)
						(arc
							(start 0.1778 -0.5715)
							(mid 0.321484 -0.511984)
							(end 0.381 -0.3683)
						)
						(arc
							(start 0.381 0.3683)
							(mid 0.321484 0.511984)
							(end 0.1778 0.5715)
						)
					)
					(width 0)
					(fill yes)
				)
			)
		)
		(pad "S" smd custom
			(at 0.98425 0.9525 90)
			(size 0.1905 0.1905)
			(layers "F.Cu" "F.Mask" "F.Paste")
			(net "GND")
			(options
				(clearance outline)
				(anchor circle)
			)
			(primitives
				(gr_poly
					(pts
						(arc
							(start -0.1778 0.5715)
							(mid -0.321484 0.511984)
							(end -0.381 0.3683)
						)
						(arc
							(start -0.381 -0.3683)
							(mid -0.321484 -0.511984)
							(end -0.1778 -0.5715)
						)
						(arc
							(start 0.1778 -0.5715)
							(mid 0.321484 -0.511984)
							(end 0.381 -0.3683)
						)
						(arc
							(start 0.381 0.3683)
							(mid 0.321484 0.511984)
							(end 0.1778 0.5715)
						)
					)
					(width 0)
					(fill yes)
				)
			)
		)
	)
	(footprint ""
		(layer "F.Cu")
		(at 259.089906 -227.82911 90)
		(property "Reference" "R167"
			(at 0 0 90)
			(layer "F.SilkS")
			(hide yes)
			(effects
				(font
					(size 1.27 1.27)
				)
			)
		)
		(property "Value" "10KR2F-2-GP"
			(at 0.064008 -3.993896 90)
			(unlocked yes)
			(layer "F.Fab")
			(hide yes)
			(effects
				(font
					(size 1.016 1.016)
					(thickness 0.1524)
				)
			)
		)
		(property "Device Type" "R402H16"
			(at 0.064008 -5.517896 90)
			(unlocked yes)
			(layer "F.Fab")
			(hide yes)
			(effects
				(font
					(size 1.016 1.016)
					(thickness 0.1524)
				)
			)
		)
		(duplicate_pad_numbers_are_jumpers no)
		(fp_line
			(start 0.508 -0.9398)
			(end -0.508 -0.9398)
			(stroke
				(width 0.1524)
				(type default)
			)
			(layer "F.SilkS")
		)
		(fp_line
			(start -0.508 -0.9398)
			(end -0.508 0.9398)
			(stroke
				(width 0.1524)
				(type default)
			)
			(layer "F.SilkS")
		)
		(fp_rect
			(start -0.508 0.9398)
			(end 0.508 -0.9398)
			(stroke
				(width 0)
				(type default)
			)
			(fill no)
			(layer "F.CrtYd")
		)
		(fp_rect
			(start -0.508 0.9398)
			(end 0.508 -0.9398)
			(stroke
				(width 0)
				(type default)
			)
			(fill no)
			(layer "F.Fab")
		)
		(pad "1" smd custom
			(at 0 -0.4445 90)
			(size 0.1397 0.1397)
			(layers "F.Cu" "F.Mask" "F.Paste")
			(net "P5V_B_3_SENSE")
			(options
				(clearance outline)
				(anchor circle)
			)
			(primitives
				(gr_poly
					(pts
						(arc
							(start -0.1778 -0.2794)
							(mid -0.249642 -0.249642)
							(end -0.2794 -0.1778)
						)
						(arc
							(start -0.2794 0.1778)
							(mid -0.249642 0.249642)
							(end -0.1778 0.2794)
						)
						(arc
							(start 0.1778 0.2794)
							(mid 0.249642 0.249642)
							(end 0.2794 0.1778)
						)
						(arc
							(start 0.2794 -0.1778)
							(mid 0.249642 -0.249642)
							(end 0.1778 -0.2794)
						)
					)
					(width 0)
					(fill yes)
				)
			)
		)
		(pad "2" smd custom
			(at 0 0.4445 90)
			(size 0.1397 0.1397)
			(layers "F.Cu" "F.Mask" "F.Paste")
			(net "GND")
			(options
				(clearance outline)
				(anchor circle)
			)
			(primitives
				(gr_poly
					(pts
						(arc
							(start -0.1778 -0.2794)
							(mid -0.249642 -0.249642)
							(end -0.2794 -0.1778)
						)
						(arc
							(start -0.2794 0.1778)
							(mid -0.249642 0.249642)
							(end -0.1778 0.2794)
						)
						(arc
							(start 0.1778 0.2794)
							(mid 0.249642 0.249642)
							(end 0.2794 0.1778)
						)
						(arc
							(start 0.2794 -0.1778)
							(mid 0.249642 -0.249642)
							(end 0.1778 -0.2794)
						)
					)
					(width 0)
					(fill yes)
				)
			)
		)
	)
)
